(kicad_pcb
	(version 20241229)
	(generator "pcbnew")
	(generator_version "9.0")
	(general
		(thickness 1.6296)
		(legacy_teardrops no)
	)
	(paper "A3")
	(title_block
		(title "Thunderbolt to 10GbE adapter")
		(date "2026-04-21")
		(rev "1.1.0")
		(company "Antmicro Ltd")
		(comment 1 "www.antmicro.com")
		(comment 9 "footprints 214-217 of 703")
	)
	(layers
		(0 "F.Cu" signal)
		(4 "In1.Cu" signal)
		(6 "In2.Cu" signal)
		(8 "In3.Cu" signal)
		(10 "In4.Cu" signal)
		(12 "In5.Cu" signal)
		(14 "In6.Cu" signal)
		(2 "B.Cu" signal)
		(9 "F.Adhes" user "F.Adhesive")
		(11 "B.Adhes" user "B.Adhesive")
		(13 "F.Paste" user)
		(15 "B.Paste" user)
		(5 "F.SilkS" user "F.Silkscreen")
		(7 "B.SilkS" user "B.Silkscreen")
		(1 "F.Mask" user)
		(3 "B.Mask" user)
		(17 "Dwgs.User" user "User.Drawings")
		(19 "Cmts.User" user "User.Comments")
		(21 "Eco1.User" user "User.Eco1")
		(23 "Eco2.User" user "User.Eco2")
		(25 "Edge.Cuts" user)
		(27 "Margin" user)
		(31 "F.CrtYd" user "F.Courtyard")
		(29 "B.CrtYd" user "B.Courtyard")
		(35 "F.Fab" user)
		(33 "B.Fab" user)
	)
	(footprint "antmicro-footprints:Conn_Molex_KK_1x4_0470531000"
		(layer "F.Cu")
		(at 118.5 83.62 90)
		(property "Reference" "J7"
			(at 9.32 2.3 180)
			(layer "F.SilkS")
			(effects
				(font
					(size 0.7 0.7)
					(thickness 0.15)
				)
				(justify left bottom)
			)
		)
		(property "Value" "Molex_KK_1x4_0470531000"
			(at 0 4.7 90)
			(layer "F.Fab")
			(effects
				(font
					(size 0.7 0.7)
					(thickness 0.15)
				)
				(justify left bottom)
			)
		)
		(property "Datasheet" "https://tools.molex.com/pdm_docs/sd/470531000_sd.pdf"
			(at 0 0 90)
			(layer "F.Fab")
			(hide yes)
			(effects
				(font
					(size 1.27 1.27)
					(thickness 0.15)
				)
			)
		)
		(property "Description" "Connector Header, THT,  4x1"
			(at 0 0 90)
			(layer "F.Fab")
			(hide yes)
			(effects
				(font
					(size 1.27 1.27)
					(thickness 0.15)
				)
			)
		)
		(property "MPN" "0470531000"
			(at 0 0 90)
			(unlocked yes)
			(layer "F.Fab")
			(hide yes)
			(effects
				(font
					(size 1 1)
					(thickness 0.15)
				)
			)
		)
		(property "Manufacturer" "Molex"
			(at 0 0 90)
			(unlocked yes)
			(layer "F.Fab")
			(hide yes)
			(effects
				(font
					(size 1 1)
					(thickness 0.15)
				)
			)
		)
		(property "Author" "Antmicro"
			(at 0 0 90)
			(unlocked yes)
			(layer "F.Fab")
			(hide yes)
			(effects
				(font
					(size 1 1)
					(thickness 0.15)
				)
			)
		)
		(property "License" "Apache-2.0"
			(at 0 0 90)
			(unlocked yes)
			(layer "F.Fab")
			(hide yes)
			(effects
				(font
					(size 1 1)
					(thickness 0.15)
				)
			)
		)
		(sheetname "/Fan controller/")
		(sheetfile "fan-controller.kicad_sch")
		(attr through_hole)
		(fp_line
			(start -1.35 -2.6)
			(end 4.4 -2.6)
			(stroke
				(width 0.15)
				(type solid)
			)
			(layer "F.SilkS")
		)
		(fp_line
			(start 8.95 -2.55)
			(end 8.95 3.4)
			(stroke
				(width 0.15)
				(type solid)
			)
			(layer "F.SilkS")
		)
		(fp_line
			(start 5.75 -2.55)
			(end 8.95 -2.55)
			(stroke
				(width 0.15)
				(type solid)
			)
			(layer "F.SilkS")
		)
		(fp_line
			(start 5.08 2.29)
			(end 5.08 3.3)
			(stroke
				(width 0.15)
				(type solid)
			)
			(layer "F.SilkS")
		)
		(fp_line
			(start 0 2.29)
			(end 5.08 2.29)
			(stroke
				(width 0.15)
				(type solid)
			)
			(layer "F.SilkS")
		)
		(fp_line
			(start 0 3.3)
			(end 0 2.29)
			(stroke
				(width 0.15)
				(type solid)
			)
			(layer "F.SilkS")
		)
		(fp_line
			(start 8.95 3.4)
			(end -1.35 3.4)
			(stroke
				(width 0.15)
				(type solid)
			)
			(layer "F.SilkS")
		)
		(fp_line
			(start -1.35 3.4)
			(end -1.35 -2.6)
			(stroke
				(width 0.15)
				(type solid)
			)
			(layer "F.SilkS")
		)
		(fp_circle
			(center 0 -3)
			(end 0.05 -3)
			(stroke
				(width 0.15)
				(type solid)
			)
			(fill yes)
			(layer "F.SilkS")
		)
		(fp_rect
			(start -1.54 -2.96)
			(end 9.16 3.55)
			(stroke
				(width 0.05)
				(type solid)
			)
			(fill no)
			(layer "F.CrtYd")
		)
		(fp_line
			(start 8.85 -2.5)
			(end 8.85 3.3)
			(stroke
				(width 0.15)
				(type solid)
			)
			(layer "F.Fab")
		)
		(fp_line
			(start 5.75 -2.5)
			(end 8.85 -2.5)
			(stroke
				(width 0.15)
				(type solid)
			)
			(layer "F.Fab")
		)
		(fp_line
			(start -1.25 -2.5)
			(end 4.4 -2.5)
			(stroke
				(width 0.15)
				(type solid)
			)
			(layer "F.Fab")
		)
		(fp_line
			(start 5.1 2.3)
			(end 0 2.3)
			(stroke
				(width 0.15)
				(type solid)
			)
			(layer "F.Fab")
		)
		(fp_line
			(start 0 2.3)
			(end 0 3.3)
			(stroke
				(width 0.15)
				(type solid)
			)
			(layer "F.Fab")
		)
		(fp_line
			(start 8.85 3.3)
			(end -1.2 3.3)
			(stroke
				(width 0.15)
				(type solid)
			)
			(layer "F.Fab")
		)
		(fp_line
			(start 5.1 3.3)
			(end 5.1 2.3)
			(stroke
				(width 0.15)
				(type solid)
			)
			(layer "F.Fab")
		)
		(fp_line
			(start -1.2 3.3)
			(end -1.25 3.3)
			(stroke
				(width 0.15)
				(type solid)
			)
			(layer "F.Fab")
		)
		(fp_line
			(start -1.25 3.3)
			(end -1.25 -2.5)
			(stroke
				(width 0.15)
				(type solid)
			)
			(layer "F.Fab")
		)
		(fp_text user "Author: Antmicro"
			(at -2.1 7.55 90)
			(layer "F.Fab")
			(effects
				(font
					(size 0.7 0.7)
					(thickness 0.15)
				)
				(justify left bottom)
			)
		)
		(fp_text user "License: Apache-2.0"
			(at -2.1 8.75 90)
			(layer "F.Fab")
			(effects
				(font
					(size 0.7 0.7)
					(thickness 0.15)
				)
				(justify left bottom)
			)
		)
		(fp_text user "${REFERENCE}"
			(at -2.1 6.35 90)
			(layer "F.Fab")
			(effects
				(font
					(size 0.7 0.7)
					(thickness 0.15)
				)
				(justify left bottom)
			)
		)
		(pad "" np_thru_hole circle
			(at 5.08 -2.16 180)
			(size 1.1 1.1)
			(drill 1.1)
			(layers "*.Cu" "*.Mask")
		)
		(pad "1" thru_hole rect
			(at 0 0 180)
			(size 2.03 1.73)
			(drill 1.02)
			(layers "*.Cu" "*.Mask")
			(remove_unused_layers no)
			(net 23 "GND")
			(pintype "passive")
		)
		(pad "2" thru_hole oval
			(at 2.54 0 180)
			(size 2.03 1.73)
			(drill 1.02)
			(layers "*.Cu" "*.Mask")
			(remove_unused_layers no)
			(net 40 "+5V")
			(pintype "passive")
		)
		(pad "3" thru_hole oval
			(at 5.08 0 180)
			(size 2.03 1.73)
			(drill 1.02)
			(layers "*.Cu" "*.Mask")
			(remove_unused_layers no)
			(net 155 "/Fan controller/TACH")
			(pintype "passive+no_connect")
		)
		(pad "4" thru_hole oval
			(at 7.62 0 180)
			(size 2.03 1.73)
			(drill 1.02)
			(layers "*.Cu" "*.Mask")
			(remove_unused_layers no)
			(net 154 "/Fan controller/PWM")
			(pintype "passive")
		)
	)
	(footprint "antmicro-footprints:LED_0603_1608Metric_G"
		(layer "F.Cu")
		(at 183.2 74.5)
		(descr "LED SMD 0603 Green")
		(tags "LED SMD 0603 Green")
		(property "Reference" "D9"
			(at -1.2 6.25 0)
			(layer "F.SilkS")
			(effects
				(font
					(size 0.7 0.7)
					(thickness 0.15)
				)
				(justify left bottom)
			)
		)
		(property "Value" "LED_G_0603_LG_L29K-G2J1-24-Z"
			(at -0.001 1.599 0)
			(layer "F.Fab")
			(effects
				(font
					(size 0.7 0.7)
					(thickness 0.15)
				)
				(justify left bottom)
			)
		)
		(property "Datasheet" "https://look.ams-osram.com/m/19ee86b3ae0ee95b/original/LG-L29K.pdf"
			(at 0 0 0)
			(layer "F.Fab")
			(hide yes)
			(effects
				(font
					(size 1.27 1.27)
					(thickness 0.15)
				)
			)
		)
		(property "Description" "LED, Green, SMD, 0603, 20 mA, 1.7 V, 570 nm"
			(at 0 0 0)
			(layer "F.Fab")
			(hide yes)
			(effects
				(font
					(size 1.27 1.27)
					(thickness 0.15)
				)
			)
		)
		(property "MPN" "LG L29K-G2J1-24-Z"
			(at 0 0 0)
			(unlocked yes)
			(layer "F.Fab")
			(hide yes)
			(effects
				(font
					(size 1 1)
					(thickness 0.15)
				)
			)
		)
		(property "Manufacturer" "OSRAM"
			(at 0 0 0)
			(unlocked yes)
			(layer "F.Fab")
			(hide yes)
			(effects
				(font
					(size 1 1)
					(thickness 0.15)
				)
			)
		)
		(property "Color" "Green"
			(at 0 0 0)
			(unlocked yes)
			(layer "F.Fab")
			(hide yes)
			(effects
				(font
					(size 1 1)
					(thickness 0.15)
				)
			)
		)
		(property "Author" "Antmicro"
			(at 0 0 0)
			(unlocked yes)
			(layer "F.Fab")
			(hide yes)
			(effects
				(font
					(size 1 1)
					(thickness 0.15)
				)
			)
		)
		(property "License" "Apache-2.0"
			(at 0 0 0)
			(unlocked yes)
			(layer "F.Fab")
			(hide yes)
			(effects
				(font
					(size 1 1)
					(thickness 0.15)
				)
			)
		)
		(sheetname "/X710 DCDC converters/")
		(sheetfile "DCDC_converters_X710.kicad_sch")
		(attr smd)
		(fp_line
			(start -1.18 -0.319)
			(end -1.18 0.321)
			(stroke
				(width 0.15)
				(type solid)
			)
			(layer "F.SilkS")
		)
		(fp_line
			(start -0.094672 0.001008)
			(end -0.24 0.001008)
			(stroke
				(width 0.1)
				(type solid)
			)
			(layer "F.SilkS")
		)
		(fp_line
			(start -0.094672 0.001008)
			(end 0.105328 -0.198992)
			(stroke
				(width 0.1)
				(type solid)
			)
			(layer "F.SilkS")
		)
		(fp_line
			(start -0.094672 0.201008)
			(end -0.094672 -0.198992)
			(stroke
				(width 0.1)
				(type solid)
			)
			(layer "F.SilkS")
		)
		(fp_line
			(start 0.105328 0.001008)
			(end 0.24 0.001)
			(stroke
				(width 0.1)
				(type solid)
			)
			(layer "F.SilkS")
		)
		(fp_line
			(start 0.105328 0.201008)
			(end -0.094672 0.001008)
			(stroke
				(width 0.1)
				(type solid)
			)
			(layer "F.SilkS")
		)
		(fp_line
			(start 0.105328 0.201008)
			(end 0.105328 -0.198992)
			(stroke
				(width 0.1)
				(type solid)
			)
			(layer "F.SilkS")
		)
		(fp_line
			(start 0.22 -0.35)
			(end -0.22 -0.35)
			(stroke
				(width 0.15)
				(type solid)
			)
			(layer "F.SilkS")
		)
		(fp_line
			(start 0.22 0.35)
			(end -0.22 0.35)
			(stroke
				(width 0.15)
				(type solid)
			)
			(layer "F.SilkS")
		)
		(fp_rect
			(start 1.25 0.65)
			(end -1.25 -0.65)
			(stroke
				(width 0.05)
				(type solid)
			)
			(fill no)
			(layer "F.CrtYd")
		)
		(fp_line
			(start -0.199 -0.202)
			(end -0.199 0.1)
			(stroke
				(width 0.15)
				(type solid)
			)
			(layer "F.Fab")
		)
		(fp_line
			(start -0.199 0)
			(end -0.597 0)
			(stroke
				(width 0.15)
				(type solid)
			)
			(layer "F.Fab")
		)
		(fp_line
			(start -0.199 0.2)
			(end -0.199 0.1)
			(stroke
				(width 0.15)
				(type solid)
			)
			(layer "F.Fab")
		)
		(fp_line
			(start -0.101 0)
			(end 0.201 0.2)
			(stroke
				(width 0.15)
				(type solid)
			)
			(layer "F.Fab")
		)
		(fp_line
			(start 0.201 -0.202)
			(end -0.101 0)
			(stroke
				(width 0.15)
				(type solid)
			)
			(layer "F.Fab")
		)
		(fp_line
			(start 0.201 0)
			(end 0.201 -0.202)
			(stroke
				(width 0.15)
				(type solid)
			)
			(layer "F.Fab")
		)
		(fp_line
			(start 0.201 0.2)
			(end 0.201 0)
			(stroke
				(width 0.15)
				(type solid)
			)
			(layer "F.Fab")
		)
		(fp_line
			(start 0.599 0)
			(end 0.201 0)
			(stroke
				(width 0.15)
				(type solid)
			)
			(layer "F.Fab")
		)
		(fp_rect
			(start 0.848 0.4)
			(end -0.85 -0.402)
			(stroke
				(width 0.15)
				(type solid)
			)
			(fill no)
			(layer "F.Fab")
		)
		(fp_text user "${REFERENCE}"
			(at -1.4224 5.999 0)
			(layer "F.Fab")
			(effects
				(font
					(size 0.7 0.7)
					(thickness 0.15)
				)
				(justify left bottom)
			)
		)
		(fp_text user "License: Apache-2.0"
			(at -1.4224 3.599 0)
			(layer "F.Fab")
			(effects
				(font
					(size 0.7 0.7)
					(thickness 0.15)
				)
				(justify left bottom)
			)
		)
		(fp_text user "Author: Antmicro"
			(at -1.4224 4.799 0)
			(layer "F.Fab")
			(effects
				(font
					(size 0.7 0.7)
					(thickness 0.15)
				)
				(justify left bottom)
			)
		)
		(pad "1" smd roundrect
			(at -0.7 0 180)
			(size 0.8 1)
			(layers "F.Cu" "F.Mask" "F.Paste")
			(roundrect_rratio 0.2)
			(net 416 "Net-(D9-C)")
			(pinfunction "C")
			(pintype "passive")
		)
		(pad "2" smd roundrect
			(at 0.7 0 180)
			(size 0.8 1)
			(layers "F.Cu" "F.Mask" "F.Paste")
			(roundrect_rratio 0.2)
			(net 334 "/X710 DCDC converters/+3V3_OUT")
			(pinfunction "A")
			(pintype "passive")
		)
	)
	(footprint "antmicro-footprints:MP_Pad6mm_Drill3.2mm"
		(layer "F.Cu")
		(at 128 108 90)
		(property "Reference" "MP5"
			(at -0.4 3.4 180)
			(layer "F.SilkS")
			(effects
				(font
					(size 0.7 0.7)
					(thickness 0.15)
				)
				(justify left bottom)
			)
		)
		(property "Value" "MP_Pad6mm_Drill3.2mm"
			(at 0 3.9 90)
			(layer "F.Fab")
			(effects
				(font
					(size 0.7 0.7)
					(thickness 0.15)
				)
				(justify left bottom)
			)
		)
		(property "Description" "Mechanical part"
			(at 0 0 90)
			(layer "F.Fab")
			(hide yes)
			(effects
				(font
					(size 1.27 1.27)
					(thickness 0.15)
				)
			)
		)
		(property "Author" "Antmicro"
			(at 0 0 90)
			(unlocked yes)
			(layer "F.Fab")
			(hide yes)
			(effects
				(font
					(size 1 1)
					(thickness 0.15)
				)
			)
		)
		(property "License" "Apache-2.0"
			(at 0 0 90)
			(unlocked yes)
			(layer "F.Fab")
			(hide yes)
			(effects
				(font
					(size 1 1)
					(thickness 0.15)
				)
			)
		)
		(sheetname "/")
		(sheetfile "thunderbolt-to-10gbe-adapter.kicad_sch")
		(attr exclude_from_pos_files exclude_from_bom)
		(fp_circle
			(center 0 0)
			(end 3.25 0)
			(stroke
				(width 0.05)
				(type default)
			)
			(fill no)
			(layer "F.CrtYd")
		)
		(fp_text user "License: Apache-2.0"
			(at -0.178 8.425 90)
			(layer "F.Fab")
			(effects
				(font
					(size 0.7 0.7)
					(thickness 0.15)
				)
				(justify left bottom)
			)
		)
		(fp_text user "${REFERENCE}"
			(at -0.178 6.025 90)
			(layer "F.Fab")
			(effects
				(font
					(size 0.7 0.7)
					(thickness 0.15)
				)
				(justify left bottom)
			)
		)
		(fp_text user "Author: Antmicro"
			(at -0.178 7.225 90)
			(layer "F.Fab")
			(effects
				(font
					(size 0.7 0.7)
					(thickness 0.15)
				)
				(justify left bottom)
			)
		)
		(pad "1" thru_hole circle
			(at 0 0 90)
			(size 6 6)
			(drill 3.2)
			(layers "*.Cu" "*.Mask")
			(remove_unused_layers no)
			(net 23 "GND")
			(pintype "passive")
		)
	)
	(footprint "antmicro-footprints:C_Pol_EIA-B"
		(layer "F.Cu")
		(at 121.2 114.5 180)
		(property "Reference" "C32"
			(at 0 -2.3 180)
			(layer "F.SilkS")
			(effects
				(font
					(size 0.7 0.7)
					(thickness 0.15)
				)
			)
		)
		(property "Value" "C_Pol_330u_6.3V_KEMET-T520-B"
			(at 0 2.85 180)
			(layer "F.Fab")
			(effects
				(font
					(size 0.7 0.7)
					(thickness 0.15)
				)
				(justify left bottom)
			)
		)
		(property "Datasheet" "https://www.kemet.com/en/us/capacitors/product/T520B337M006ATE040.html"
			(at 0 0 180)
			(layer "F.Fab")
			(hide yes)
			(effects
				(font
					(size 1.27 1.27)
					(thickness 0.15)
				)
			)
		)
		(property "Description" "Tantalum Polymer Capacitor, KO-CAP®, 330 µF, ± 20%, 6.3 V, B, 0.04 ohm, 1411 [3528 Metric]"
			(at 0 0 180)
			(layer "F.Fab")
			(hide yes)
			(effects
				(font
					(size 1.27 1.27)
					(thickness 0.15)
				)
			)
		)
		(property "Val" "330u"
			(at 0 0 180)
			(unlocked yes)
			(layer "F.Fab")
			(hide yes)
			(effects
				(font
					(size 1 1)
					(thickness 0.15)
				)
			)
		)
		(property "MPN" "T520B337M006ATE040"
			(at 0 0 180)
			(unlocked yes)
			(layer "F.Fab")
			(hide yes)
			(effects
				(font
					(size 1 1)
					(thickness 0.15)
				)
			)
		)
		(property "Manufacturer" "KEMET"
			(at 0 0 180)
			(unlocked yes)
			(layer "F.Fab")
			(hide yes)
			(effects
				(font
					(size 1 1)
					(thickness 0.15)
				)
			)
		)
		(property "License" "Apache-2.0"
			(at 0 0 180)
			(unlocked yes)
			(layer "F.Fab")
			(hide yes)
			(effects
				(font
					(size 1 1)
					(thickness 0.15)
				)
			)
		)
		(property "Author" "Antmicro"
			(at 0 0 180)
			(unlocked yes)
			(layer "F.Fab")
			(hide yes)
			(effects
				(font
					(size 1 1)
					(thickness 0.15)
				)
			)
		)
		(property "Voltage" "6.3V"
			(at 0 0 180)
			(unlocked yes)
			(layer "F.Fab")
			(hide yes)
			(effects
				(font
					(size 1 1)
					(thickness 0.15)
				)
			)
		)
		(property "Dielectric" "template_dielectric"
			(at 0 0 180)
			(unlocked yes)
			(layer "F.Fab")
			(hide yes)
			(effects
				(font
					(size 1 1)
					(thickness 0.15)
				)
			)
		)
		(sheetname "/PD and TB DC-DC/")
		(sheetfile "PD_and_TB_DC_DC.kicad_sch")
		(attr smd)
		(fp_line
			(start 1.8 1.6)
			(end -1.8 1.6)
			(stroke
				(width 0.15)
				(type solid)
			)
			(layer "F.SilkS")
		)
		(fp_line
			(start 1.8 1.3)
			(end 1.8 1.6)
			(stroke
				(width 0.15)
				(type solid)
			)
			(layer "F.SilkS")
		)
		(fp_line
			(start 1.8 -1.3)
			(end 1.8 -1.6)
			(stroke
				(width 0.15)
				(type solid)
			)
			(layer "F.SilkS")
		)
		(fp_line
			(start -1.8 1.3)
			(end -1.8 1.6)
			(stroke
				(width 0.15)
				(type solid)
			)
			(layer "F.SilkS")
		)
		(fp_line
			(start -1.8 -1.3)
			(end -1.8 -1.6)
			(stroke
				(width 0.15)
				(type solid)
			)
			(layer "F.SilkS")
		)
		(fp_line
			(start -1.8 -1.6)
			(end 1.8 -1.6)
			(stroke
				(width 0.15)
				(type solid)
			)
			(layer "F.SilkS")
		)
		(fp_line
			(start -2.325 -1.475)
			(end -2.325 -1.878)
			(stroke
				(width 0.15)
				(type solid)
			)
			(layer "F.SilkS")
		)
		(fp_line
			(start -2.521 -1.676)
			(end -2.123 -1.676)
			(stroke
				(width 0.15)
				(type solid)
			)
			(layer "F.SilkS")
		)
		(fp_line
			(start 2.4 1.35)
			(end 1.96 1.35)
			(stroke
				(width 0.05)
				(type solid)
			)
			(layer "F.CrtYd")
		)
		(fp_line
			(start 2.399 -1.35)
			(end 2.4 1.35)
			(stroke
				(width 0.05)
				(type solid)
			)
			(layer "F.CrtYd")
		)
		(fp_line
			(start 2.399 -1.35)
			(end 1.959 -1.35)
			(stroke
				(width 0.05)
				(type solid)
			)
			(layer "F.CrtYd")
		)
		(fp_line
			(start 1.96 1.75)
			(end -1.97 1.75)
			(stroke
				(width 0.05)
				(type solid)
			)
			(layer "F.CrtYd")
		)
		(fp_line
			(start 1.96 1.35)
			(end 1.96 1.75)
			(stroke
				(width 0.05)
				(type solid)
			)
			(layer "F.CrtYd")
		)
		(fp_line
			(start 1.959 -1.75)
			(end 1.959 -1.35)
			(stroke
				(width 0.05)
				(type solid)
			)
			(layer "F.CrtYd")
		)
		(fp_line
			(start 1.959 -1.75)
			(end -1.97 -1.75)
			(stroke
				(width 0.05)
				(type solid)
			)
			(layer "F.CrtYd")
		)
		(fp_line
			(start -1.97 1.35)
			(end -1.97 1.75)
			(stroke
				(width 0.05)
				(type solid)
			)
			(layer "F.CrtYd")
		)
		(fp_line
			(start -1.97 1.35)
			(end -2.41 1.35)
			(stroke
				(width 0.05)
				(type solid)
			)
			(layer "F.CrtYd")
		)
		(fp_line
			(start -1.97 -1.35)
			(end -2.41 -1.35)
			(stroke
				(width 0.05)
				(type solid)
			)
			(layer "F.CrtYd")
		)
		(fp_line
			(start -1.97 -1.75)
			(end -1.97 -1.35)
			(stroke
				(width 0.05)
				(type solid)
			)
			(layer "F.CrtYd")
		)
		(fp_line
			(start -2.411 -1.35)
			(end -2.41 1.35)
			(stroke
				(width 0.05)
				(type solid)
			)
			(layer "F.CrtYd")
		)
		(fp_line
			(start -1.7 1.324)
			(end -1.551 1.475)
			(stroke
				(width 0.15)
				(type solid)
			)
			(layer "F.Fab")
		)
		(fp_rect
			(start -1.72 -1.5)
			(end 1.719 1.499)
			(stroke
				(width 0.15)
				(type solid)
			)
			(fill no)
			(layer "F.Fab")
		)
		(fp_text user "License: Apache-2.0"
			(at -2.665 5.65 180)
			(layer "F.Fab")
			(effects
				(font
					(size 0.7 0.7)
					(thickness 0.15)
				)
				(justify left bottom)
			)
		)
		(fp_text user "Author: Antmicro"
			(at -2.665 6.85 180)
			(layer "F.Fab")
			(effects
				(font
					(size 0.7 0.7)
					(thickness 0.15)
				)
				(justify left bottom)
			)
		)
		(fp_text user "${REFERENCE}"
			(at -2.665 4.45 180)
			(layer "F.Fab")
			(effects
				(font
					(size 0.7 0.7)
					(thickness 0.15)
				)
				(justify left bottom)
			)
		)
		(pad "1" smd roundrect
			(at -1.551 0 180)
			(size 1.2 2.2)
			(layers "F.Cu" "F.Mask" "F.Paste")
			(roundrect_rratio 0.1)
			(net 57 "+3V3_TB")
			(pintype "passive")
		)
		(pad "2" smd roundrect
			(at 1.55 0 180)
			(size 1.2 2.2)
			(layers "F.Cu" "F.Mask" "F.Paste")
			(roundrect_rratio 0.1)
			(net 23 "GND")
			(pintype "passive")
		)
	)
)
